(kicad_pcb
	(version 20260206)
	(generator "pcbnew")
	(generator_version "10.0")
	(general
		(thickness 1.6)
		(legacy_teardrops no)
	)
	(paper "A4")
	(title_block
		(title "baseboard — 13948-1b.1110WZS1818.brd")
		(comment 1 "Honey Badger (Wiwynn) / footprints 923-929 of 2523")
	)
	(layers
		(0 "F.Cu" signal "TOP")
		(4 "In1.Cu" signal "L2GND")
		(6 "In2.Cu" signal "L3")
		(8 "In3.Cu" signal "L4VCC")
		(10 "In4.Cu" signal "L5VCC")
		(12 "In5.Cu" signal "L6")
		(14 "In6.Cu" signal "L7GND")
		(2 "B.Cu" signal "BOTTOM")
		(9 "F.Adhes" user "F.Adhesive")
		(11 "B.Adhes" user "B.Adhesive")
		(13 "F.Paste" user "Package Geometry/Pastemask Top")
		(15 "B.Paste" user "Package Geometry/Pastemask Bottom")
		(5 "F.SilkS" user "Ref Des/Silkscreen Top")
		(7 "B.SilkS" user "Ref Des/Silkscreen Bottom")
		(1 "F.Mask" user "Board Geometry/Soldermask Top")
		(3 "B.Mask" user "Board Geometry/Soldermask Bottom")
		(17 "Dwgs.User" user "User.Drawings")
		(19 "Cmts.User" user "User.Comments")
		(21 "Eco1.User" user "User.Eco1")
		(23 "Eco2.User" user "User.Eco2")
		(25 "Edge.Cuts" user "Board Geometry/Outline")
		(27 "Margin" user)
		(31 "F.CrtYd" user "Package Geometry/Place Bound Top")
		(29 "B.CrtYd" user "Package Geometry/Place Bound Bottom")
		(35 "F.Fab" user "Ref Des/Assembly Top")
		(33 "B.Fab" user "Ref Des/Assembly Bottom")
	)
	(footprint ""
		(layer "F.Cu")
		(at 166.846504 -24.184356 180)
		(property "Reference" "R414"
			(at 0 0 180)
			(layer "F.SilkS")
			(hide yes)
			(effects
				(font
					(size 1.27 1.27)
				)
			)
		)
		(property "Value" "0R2J-2-GP"
			(at 0.064008 -3.993896 180)
			(unlocked yes)
			(layer "F.Fab")
			(hide yes)
			(effects
				(font
					(size 1.016 1.016)
					(thickness 0.1524)
				)
			)
		)
		(property "Device Type" "R402H16"
			(at 0.064008 -5.517896 180)
			(unlocked yes)
			(layer "F.Fab")
			(hide yes)
			(effects
				(font
					(size 1.016 1.016)
					(thickness 0.1524)
				)
			)
		)
		(duplicate_pad_numbers_are_jumpers no)
		(fp_line
			(start 0.508 -0.9398)
			(end -0.508 -0.9398)
			(stroke
				(width 0.1524)
				(type default)
			)
			(layer "F.SilkS")
		)
		(fp_line
			(start -0.508 -0.9398)
			(end -0.508 0.9398)
			(stroke
				(width 0.1524)
				(type default)
			)
			(layer "F.SilkS")
		)
		(fp_rect
			(start -0.508 0.9398)
			(end 0.508 -0.9398)
			(stroke
				(width 0)
				(type default)
			)
			(fill no)
			(layer "F.CrtYd")
		)
		(fp_rect
			(start -0.508 0.9398)
			(end 0.508 -0.9398)
			(stroke
				(width 0)
				(type default)
			)
			(fill no)
			(layer "F.Fab")
		)
		(pad "1" smd custom
			(at 0 -0.4445 180)
			(size 0.1397 0.1397)
			(layers "F.Cu" "F.Mask" "F.Paste")
			(net "RJ45_GND_7")
			(options
				(clearance outline)
				(anchor circle)
			)
			(primitives
				(gr_poly
					(pts
						(arc
							(start -0.1778 -0.2794)
							(mid -0.249642 -0.249642)
							(end -0.2794 -0.1778)
						)
						(arc
							(start -0.2794 0.1778)
							(mid -0.249642 0.249642)
							(end -0.1778 0.2794)
						)
						(arc
							(start 0.1778 0.2794)
							(mid 0.249642 0.249642)
							(end 0.2794 0.1778)
						)
						(arc
							(start 0.2794 -0.1778)
							(mid 0.249642 -0.249642)
							(end 0.1778 -0.2794)
						)
					)
					(width 0)
					(fill yes)
				)
			)
		)
		(pad "2" smd custom
			(at 0 0.4445 180)
			(size 0.1397 0.1397)
			(layers "F.Cu" "F.Mask" "F.Paste")
			(net "GND")
			(options
				(clearance outline)
				(anchor circle)
			)
			(primitives
				(gr_poly
					(pts
						(arc
							(start -0.1778 -0.2794)
							(mid -0.249642 -0.249642)
							(end -0.2794 -0.1778)
						)
						(arc
							(start -0.2794 0.1778)
							(mid -0.249642 0.249642)
							(end -0.1778 0.2794)
						)
						(arc
							(start 0.1778 0.2794)
							(mid 0.249642 0.249642)
							(end 0.2794 0.1778)
						)
						(arc
							(start 0.2794 -0.1778)
							(mid 0.249642 -0.249642)
							(end 0.1778 -0.2794)
						)
					)
					(width 0)
					(fill yes)
				)
			)
		)
	)
	(footprint ""
		(layer "F.Cu")
		(at 317.6524 -212.6234 180)
		(property "Reference" "R573"
			(at 0 0 180)
			(layer "F.SilkS")
			(hide yes)
			(effects
				(font
					(size 1.27 1.27)
				)
			)
		)
		(property "Value" "10KR2F-2-GP"
			(at 0.064008 -3.993896 180)
			(unlocked yes)
			(layer "F.Fab")
			(hide yes)
			(effects
				(font
					(size 1.016 1.016)
					(thickness 0.1524)
				)
			)
		)
		(property "Device Type" "R402H16"
			(at 0.064008 -5.517896 180)
			(unlocked yes)
			(layer "F.Fab")
			(hide yes)
			(effects
				(font
					(size 1.016 1.016)
					(thickness 0.1524)
				)
			)
		)
		(duplicate_pad_numbers_are_jumpers no)
		(fp_line
			(start 0.508 -0.9398)
			(end -0.508 -0.9398)
			(stroke
				(width 0.1524)
				(type default)
			)
			(layer "F.SilkS")
		)
		(fp_line
			(start -0.508 -0.9398)
			(end -0.508 0.9398)
			(stroke
				(width 0.1524)
				(type default)
			)
			(layer "F.SilkS")
		)
		(fp_rect
			(start -0.508 0.9398)
			(end 0.508 -0.9398)
			(stroke
				(width 0)
				(type default)
			)
			(fill no)
			(layer "F.CrtYd")
		)
		(fp_rect
			(start -0.508 0.9398)
			(end 0.508 -0.9398)
			(stroke
				(width 0)
				(type default)
			)
			(fill no)
			(layer "F.Fab")
		)
		(pad "1" smd custom
			(at 0 -0.4445 180)
			(size 0.1397 0.1397)
			(layers "F.Cu" "F.Mask" "F.Paste")
			(net "P1V8_STBY")
			(options
				(clearance outline)
				(anchor circle)
			)
			(primitives
				(gr_poly
					(pts
						(arc
							(start -0.1778 -0.2794)
							(mid -0.249642 -0.249642)
							(end -0.2794 -0.1778)
						)
						(arc
							(start -0.2794 0.1778)
							(mid -0.249642 0.249642)
							(end -0.1778 0.2794)
						)
						(arc
							(start 0.1778 0.2794)
							(mid 0.249642 0.249642)
							(end 0.2794 0.1778)
						)
						(arc
							(start 0.2794 -0.1778)
							(mid 0.249642 -0.249642)
							(end 0.1778 -0.2794)
						)
					)
					(width 0)
					(fill yes)
				)
			)
		)
		(pad "2" smd custom
			(at 0 0.4445 180)
			(size 0.1397 0.1397)
			(layers "F.Cu" "F.Mask" "F.Paste")
			(net "EXP_TDO_EN")
			(options
				(clearance outline)
				(anchor circle)
			)
			(primitives
				(gr_poly
					(pts
						(arc
							(start -0.1778 -0.2794)
							(mid -0.249642 -0.249642)
							(end -0.2794 -0.1778)
						)
						(arc
							(start -0.2794 0.1778)
							(mid -0.249642 0.249642)
							(end -0.1778 0.2794)
						)
						(arc
							(start 0.1778 0.2794)
							(mid 0.249642 0.249642)
							(end 0.2794 0.1778)
						)
						(arc
							(start 0.2794 -0.1778)
							(mid 0.249642 -0.249642)
							(end 0.1778 -0.2794)
						)
					)
					(width 0)
					(fill yes)
				)
			)
		)
	)
	(footprint ""
		(layer "F.Cu")
		(at 171.365164 -22.490176 180)
		(property "Reference" "R403"
			(at 0 0 180)
			(layer "F.SilkS")
			(hide yes)
			(effects
				(font
					(size 1.27 1.27)
				)
			)
		)
		(property "Value" "0R2J-2-GP"
			(at 0.064008 -3.993896 180)
			(unlocked yes)
			(layer "F.Fab")
			(hide yes)
			(effects
				(font
					(size 1.016 1.016)
					(thickness 0.1524)
				)
			)
		)
		(property "Device Type" "R402H16"
			(at 0.064008 -5.517896 180)
			(unlocked yes)
			(layer "F.Fab")
			(hide yes)
			(effects
				(font
					(size 1.016 1.016)
					(thickness 0.1524)
				)
			)
		)
		(duplicate_pad_numbers_are_jumpers no)
		(fp_line
			(start 0.508 -0.9398)
			(end -0.508 -0.9398)
			(stroke
				(width 0.1524)
				(type default)
			)
			(layer "F.SilkS")
		)
		(fp_line
			(start -0.508 -0.9398)
			(end -0.508 0.9398)
			(stroke
				(width 0.1524)
				(type default)
			)
			(layer "F.SilkS")
		)
		(fp_rect
			(start -0.508 0.9398)
			(end 0.508 -0.9398)
			(stroke
				(width 0)
				(type default)
			)
			(fill no)
			(layer "F.CrtYd")
		)
		(fp_rect
			(start -0.508 0.9398)
			(end 0.508 -0.9398)
			(stroke
				(width 0)
				(type default)
			)
			(fill no)
			(layer "F.Fab")
		)
		(pad "1" smd custom
			(at 0 -0.4445 180)
			(size 0.1397 0.1397)
			(layers "F.Cu" "F.Mask" "F.Paste")
			(net "P3V3_STBY")
			(options
				(clearance outline)
				(anchor circle)
			)
			(primitives
				(gr_poly
					(pts
						(arc
							(start -0.1778 -0.2794)
							(mid -0.249642 -0.249642)
							(end -0.2794 -0.1778)
						)
						(arc
							(start -0.2794 0.1778)
							(mid -0.249642 0.249642)
							(end -0.1778 0.2794)
						)
						(arc
							(start 0.1778 0.2794)
							(mid 0.249642 0.249642)
							(end 0.2794 0.1778)
						)
						(arc
							(start 0.2794 -0.1778)
							(mid 0.249642 -0.249642)
							(end 0.1778 -0.2794)
						)
					)
					(width 0)
					(fill yes)
				)
			)
		)
		(pad "2" smd custom
			(at 0 0.4445 180)
			(size 0.1397 0.1397)
			(layers "F.Cu" "F.Mask" "F.Paste")
			(net "MOD_IMC_FAB_D_COP")
			(options
				(clearance outline)
				(anchor circle)
			)
			(primitives
				(gr_poly
					(pts
						(arc
							(start -0.1778 -0.2794)
							(mid -0.249642 -0.249642)
							(end -0.2794 -0.1778)
						)
						(arc
							(start -0.2794 0.1778)
							(mid -0.249642 0.249642)
							(end -0.1778 0.2794)
						)
						(arc
							(start 0.1778 0.2794)
							(mid 0.249642 0.249642)
							(end 0.2794 0.1778)
						)
						(arc
							(start 0.2794 -0.1778)
							(mid 0.249642 -0.249642)
							(end 0.1778 -0.2794)
						)
					)
					(width 0)
					(fill yes)
				)
			)
		)
	)
	(footprint ""
		(layer "F.Cu")
		(at 317.8048 -53.2638 90)
		(property "Reference" "C281"
			(at 0 0 90)
			(layer "F.SilkS")
			(hide yes)
			(effects
				(font
					(size 1.27 1.27)
				)
			)
		)
		(property "Value" "SC1U25V3KX-GP"
			(at 0 -2.8194 90)
			(unlocked yes)
			(layer "F.Fab")
			(hide yes)
			(effects
				(font
					(size 1.016 1.016)
					(thickness 0.1524)
				)
			)
		)
		(property "Device Type" "C603H36"
			(at 0 -4.3434 90)
			(unlocked yes)
			(layer "F.Fab")
			(hide yes)
			(effects
				(font
					(size 1.016 1.016)
					(thickness 0.1524)
				)
			)
		)
		(duplicate_pad_numbers_are_jumpers no)
		(fp_line
			(start 0.508 0)
			(end -0.508 0)
			(stroke
				(width 0.2032)
				(type default)
			)
			(layer "F.SilkS")
		)
		(fp_rect
			(start -0.5842 1.3335)
			(end 0.5842 -1.3335)
			(stroke
				(width 0)
				(type default)
			)
			(fill no)
			(layer "F.CrtYd")
		)
		(fp_rect
			(start -0.5842 1.3335)
			(end 0.5842 -1.3335)
			(stroke
				(width 0)
				(type default)
			)
			(fill no)
			(layer "F.Fab")
		)
		(pad "1" smd custom
			(at 0 -0.762 90)
			(size 0.2159 0.2159)
			(layers "F.Cu" "F.Mask" "F.Paste")
			(net "P5V_STBY")
			(options
				(clearance outline)
				(anchor circle)
			)
			(primitives
				(gr_poly
					(pts
						(arc
							(start -0.3302 -0.4318)
							(mid -0.402042 -0.402042)
							(end -0.4318 -0.3302)
						)
						(arc
							(start -0.4318 0.3302)
							(mid -0.402042 0.402042)
							(end -0.3302 0.4318)
						)
						(arc
							(start 0.3302 0.4318)
							(mid 0.402042 0.402042)
							(end 0.4318 0.3302)
						)
						(arc
							(start 0.4318 -0.3302)
							(mid 0.402042 -0.402042)
							(end 0.3302 -0.4318)
						)
					)
					(width 0)
					(fill yes)
				)
			)
		)
		(pad "2" smd custom
			(at 0 0.762 90)
			(size 0.2159 0.2159)
			(layers "F.Cu" "F.Mask" "F.Paste")
			(net "GND")
			(options
				(clearance outline)
				(anchor circle)
			)
			(primitives
				(gr_poly
					(pts
						(arc
							(start -0.3302 -0.4318)
							(mid -0.402042 -0.402042)
							(end -0.4318 -0.3302)
						)
						(arc
							(start -0.4318 0.3302)
							(mid -0.402042 0.402042)
							(end -0.3302 0.4318)
						)
						(arc
							(start 0.3302 0.4318)
							(mid 0.402042 0.402042)
							(end 0.4318 0.3302)
						)
						(arc
							(start 0.4318 -0.3302)
							(mid 0.402042 -0.402042)
							(end 0.3302 -0.4318)
						)
					)
					(width 0)
					(fill yes)
				)
			)
		)
	)
	(footprint ""
		(layer "F.Cu")
		(at 151.003 -61.468)
		(property "Reference" "SC914"
			(at 0 0 0)
			(layer "F.SilkS")
			(hide yes)
			(effects
				(font
					(size 1.27 1.27)
				)
			)
		)
		(property "Value" "SCD1U16V2KX-3GP"
			(at 1.1811 -2.7051 0)
			(unlocked yes)
			(layer "F.Fab")
			(hide yes)
			(effects
				(font
					(size 1.016 1.016)
					(thickness 0.1524)
				)
			)
		)
		(property "Device Type" "C402H22"
			(at 1.1811 -4.2291 0)
			(unlocked yes)
			(layer "F.Fab")
			(hide yes)
			(effects
				(font
					(size 1.016 1.016)
					(thickness 0.1524)
				)
			)
		)
		(duplicate_pad_numbers_are_jumpers no)
		(fp_rect
			(start -0.4318 0.9525)
			(end 0.4318 -0.9525)
			(stroke
				(width 0)
				(type default)
			)
			(fill no)
			(layer "F.CrtYd")
		)
		(fp_rect
			(start -0.4318 0.9525)
			(end 0.4318 -0.9525)
			(stroke
				(width 0)
				(type default)
			)
			(fill no)
			(layer "F.Fab")
		)
		(pad "1" smd custom
			(at 0 -0.4445)
			(size 0.1524 0.1524)
			(layers "F.Cu" "F.Mask" "F.Paste")
			(net "P1V8_C")
			(options
				(clearance outline)
				(anchor circle)
			)
			(primitives
				(gr_poly
					(pts
						(arc
							(start 0.3048 -0.2032)
							(mid 0.275042 -0.275042)
							(end 0.2032 -0.3048)
						)
						(arc
							(start -0.2032 -0.3048)
							(mid -0.275042 -0.275042)
							(end -0.3048 -0.2032)
						)
						(arc
							(start -0.3048 0.2032)
							(mid -0.275042 0.275042)
							(end -0.2032 0.3048)
						)
						(arc
							(start 0.2032 0.3048)
							(mid 0.275042 0.275042)
							(end 0.3048 0.2032)
						)
					)
					(width 0)
					(fill yes)
				)
			)
		)
		(pad "2" smd custom
			(at 0 0.4445)
			(size 0.1524 0.1524)
			(layers "F.Cu" "F.Mask" "F.Paste")
			(net "GND")
			(options
				(clearance outline)
				(anchor circle)
			)
			(primitives
				(gr_poly
					(pts
						(arc
							(start 0.3048 -0.2032)
							(mid 0.275042 -0.275042)
							(end 0.2032 -0.3048)
						)
						(arc
							(start -0.2032 -0.3048)
							(mid -0.275042 -0.275042)
							(end -0.3048 -0.2032)
						)
						(arc
							(start -0.3048 0.2032)
							(mid -0.275042 0.275042)
							(end -0.2032 0.3048)
						)
						(arc
							(start 0.2032 0.3048)
							(mid 0.275042 0.275042)
							(end 0.3048 0.2032)
						)
					)
					(width 0)
					(fill yes)
				)
			)
		)
	)
	(footprint ""
		(layer "F.Cu")
		(at 44.577 -230.759)
		(property "Reference" "C301"
			(at 0 0 0)
			(layer "F.SilkS")
			(hide yes)
			(effects
				(font
					(size 1.27 1.27)
				)
			)
		)
		(property "Value" "SCD1U25V2KX-2-GP"
			(at 1.1811 -2.7051 0)
			(unlocked yes)
			(layer "F.Fab")
			(hide yes)
			(effects
				(font
					(size 1.016 1.016)
					(thickness 0.1524)
				)
			)
		)
		(property "Device Type" "C402H22"
			(at 1.1811 -4.2291 0)
			(unlocked yes)
			(layer "F.Fab")
			(hide yes)
			(effects
				(font
					(size 1.016 1.016)
					(thickness 0.1524)
				)
			)
		)
		(duplicate_pad_numbers_are_jumpers no)
		(fp_rect
			(start -0.4318 0.9525)
			(end 0.4318 -0.9525)
			(stroke
				(width 0)
				(type default)
			)
			(fill no)
			(layer "F.CrtYd")
		)
		(fp_rect
			(start -0.4318 0.9525)
			(end 0.4318 -0.9525)
			(stroke
				(width 0)
				(type default)
			)
			(fill no)
			(layer "F.Fab")
		)
		(pad "1" smd custom
			(at 0 -0.4445)
			(size 0.1524 0.1524)
			(layers "F.Cu" "F.Mask" "F.Paste")
			(net "P12V_PCIE")
			(options
				(clearance outline)
				(anchor circle)
			)
			(primitives
				(gr_poly
					(pts
						(arc
							(start 0.3048 -0.2032)
							(mid 0.275042 -0.275042)
							(end 0.2032 -0.3048)
						)
						(arc
							(start -0.2032 -0.3048)
							(mid -0.275042 -0.275042)
							(end -0.3048 -0.2032)
						)
						(arc
							(start -0.3048 0.2032)
							(mid -0.275042 0.275042)
							(end -0.2032 0.3048)
						)
						(arc
							(start 0.2032 0.3048)
							(mid 0.275042 0.275042)
							(end 0.3048 0.2032)
						)
					)
					(width 0)
					(fill yes)
				)
			)
		)
		(pad "2" smd custom
			(at 0 0.4445)
			(size 0.1524 0.1524)
			(layers "F.Cu" "F.Mask" "F.Paste")
			(net "GND")
			(options
				(clearance outline)
				(anchor circle)
			)
			(primitives
				(gr_poly
					(pts
						(arc
							(start 0.3048 -0.2032)
							(mid 0.275042 -0.275042)
							(end 0.2032 -0.3048)
						)
						(arc
							(start -0.2032 -0.3048)
							(mid -0.275042 -0.275042)
							(end -0.3048 -0.2032)
						)
						(arc
							(start -0.3048 0.2032)
							(mid -0.275042 0.275042)
							(end -0.2032 0.3048)
						)
						(arc
							(start 0.2032 0.3048)
							(mid 0.275042 0.275042)
							(end 0.3048 0.2032)
						)
					)
					(width 0)
					(fill yes)
				)
			)
		)
	)
	(footprint ""
		(layer "F.Cu")
		(at 76.748386 -108.630212 180)
		(property "Reference" "PC191"
			(at 0 0 180)
			(layer "F.SilkS")
			(hide yes)
			(effects
				(font
					(size 1.27 1.27)
				)
			)
		)
		(property "Value" "SCD47U25V3KX-3-GP"
			(at 0 -2.8194 180)
			(unlocked yes)
			(layer "F.Fab")
			(hide yes)
			(effects
				(font
					(size 1.016 1.016)
					(thickness 0.1524)
				)
			)
		)
		(property "Device Type" "C603H36"
			(at 0 -4.3434 180)
			(unlocked yes)
			(layer "F.Fab")
			(hide yes)
			(effects
				(font
					(size 1.016 1.016)
					(thickness 0.1524)
				)
			)
		)
		(duplicate_pad_numbers_are_jumpers no)
		(fp_line
			(start 0.508 0)
			(end -0.508 0)
			(stroke
				(width 0.2032)
				(type default)
			)
			(layer "F.SilkS")
		)
		(fp_rect
			(start -0.5842 1.3335)
			(end 0.5842 -1.3335)
			(stroke
				(width 0)
				(type default)
			)
			(fill no)
			(layer "F.CrtYd")
		)
		(fp_rect
			(start -0.5842 1.3335)
			(end 0.5842 -1.3335)
			(stroke
				(width 0)
				(type default)
			)
			(fill no)
			(layer "F.Fab")
		)
		(pad "1" smd custom
			(at 0 -0.762 180)
			(size 0.2159 0.2159)
			(layers "F.Cu" "F.Mask" "F.Paste")
			(net "P1V8_EN_LV")
			(options
				(clearance outline)
				(anchor circle)
			)
			(primitives
				(gr_poly
					(pts
						(arc
							(start -0.3302 -0.4318)
							(mid -0.402042 -0.402042)
							(end -0.4318 -0.3302)
						)
						(arc
							(start -0.4318 0.3302)
							(mid -0.402042 0.402042)
							(end -0.3302 0.4318)
						)
						(arc
							(start 0.3302 0.4318)
							(mid 0.402042 0.402042)
							(end 0.4318 0.3302)
						)
						(arc
							(start 0.4318 -0.3302)
							(mid 0.402042 -0.402042)
							(end 0.3302 -0.4318)
						)
					)
					(width 0)
					(fill yes)
				)
			)
		)
		(pad "2" smd custom
			(at 0 0.762 180)
			(size 0.2159 0.2159)
			(layers "F.Cu" "F.Mask" "F.Paste")
			(net "P1V8_E")
			(options
				(clearance outline)
				(anchor circle)
			)
			(primitives
				(gr_poly
					(pts
						(arc
							(start -0.3302 -0.4318)
							(mid -0.402042 -0.402042)
							(end -0.4318 -0.3302)
						)
						(arc
							(start -0.4318 0.3302)
							(mid -0.402042 0.402042)
							(end -0.3302 0.4318)
						)
						(arc
							(start 0.3302 0.4318)
							(mid 0.402042 0.402042)
							(end 0.4318 0.3302)
						)
						(arc
							(start 0.4318 -0.3302)
							(mid 0.402042 -0.402042)
							(end 0.3302 -0.4318)
						)
					)
					(width 0)
					(fill yes)
				)
			)
		)
	)
)
